# T6G (Grand Teton) — schematic netlist excerpt (pin names and nets, part order shuffled) for the footprints in the layout excerpt that follows; sources: Cadence DE-HDL packaged netlist, KiCad conversion of 04192023_DAF0TMB3IC0_F0TG_MB_C_brd_V02_OCP.brd

C168  Q_CAP  0.1UF 25V 10% X7R  pkg 0402  page 106 : A = P3V3_AUX ; B = GND
R1159  Q_RES  0 5% CHIP  pkg 0402LF  page 161 : A = SMB_CPU0_SEC_R_SCL ; B = SMB_CPU0_SEC_SCL

(kicad_pcb
	(version 20260206)
	(generator "pcbnew")
	(generator_version "10.0")
	(general
		(thickness 1.6)
		(legacy_teardrops no)
	)
	(paper "A4")
	(title_block
		(title "04192023_DAF0TMB3IC0_F0TG_MB_C_brd_V02_OCP.brd")
		(comment 1 "Grand Teton / footprints 7378-7379 of 8354")
	)
	(layers
		(0 "F.Cu" signal "TOP")
		(4 "In1.Cu" signal "GND")
		(6 "In2.Cu" signal "IN1")
		(8 "In3.Cu" signal "GND1")
		(10 "In4.Cu" signal "IN2")
		(12 "In5.Cu" signal "GND2")
		(14 "In6.Cu" signal "IN3")
		(16 "In7.Cu" signal "GND3")
		(18 "In8.Cu" signal "VCC")
		(20 "In9.Cu" signal "VCC1")
		(22 "In10.Cu" signal "GND4")
		(24 "In11.Cu" signal "IN4")
		(26 "In12.Cu" signal "GND5")
		(28 "In13.Cu" signal "IN5")
		(30 "In14.Cu" signal "GND6")
		(32 "In15.Cu" signal "IN6")
		(34 "In16.Cu" signal "GND7")
		(2 "B.Cu" signal "BOTTOM")
		(9 "F.Adhes" user "F.Adhesive")
		(11 "B.Adhes" user "B.Adhesive")
		(13 "F.Paste" user "Package Geometry/Pastemask Top")
		(15 "B.Paste" user "Package Geometry/Pastemask Bottom")
		(5 "F.SilkS" user "Ref Des/Silkscreen Top")
		(7 "B.SilkS" user "Ref Des/Silkscreen Bottom")
		(1 "F.Mask" user "Board Geometry/Soldermask Top")
		(3 "B.Mask" user "Board Geometry/Soldermask Bottom")
		(17 "Dwgs.User" user "User.Drawings")
		(19 "Cmts.User" user "User.Comments")
		(21 "Eco1.User" user "User.Eco1")
		(23 "Eco2.User" user "User.Eco2")
		(25 "Edge.Cuts" user "Board Geometry/Outline")
		(27 "Margin" user)
		(31 "F.CrtYd" user "Package Geometry/Place Bound Top")
		(29 "B.CrtYd" user "Package Geometry/Place Bound Bottom")
		(35 "F.Fab" user "Ref Des/Assembly Top")
		(33 "B.Fab" user "Ref Des/Assembly Bottom")
	)
	(footprint ""
		(layer "B.Cu")
		(at 182.860442 -193.996564)
		(property "Reference" "C168"
			(at 0 0 0)
			(layer "B.SilkS")
			(hide yes)
			(effects
				(font
					(size 1.27 1.27)
				)
				(justify mirror)
			)
		)
		(property "Value" ""
			(at 0 0 0)
			(layer "B.Fab")
			(effects
				(font
					(size 1.27 1.27)
				)
				(justify mirror)
			)
		)
		(duplicate_pad_numbers_are_jumpers no)
		(fp_line
			(start -0.7874 -0.4064)
			(end -0.7874 0.4064)
			(stroke
				(width 0.1524)
				(type default)
			)
			(layer "B.SilkS")
		)
		(fp_line
			(start -0.7874 0.4064)
			(end 0.7874 0.4064)
			(stroke
				(width 0.1524)
				(type default)
			)
			(layer "B.SilkS")
		)
		(fp_line
			(start 0.7874 -0.4064)
			(end -0.7874 -0.4064)
			(stroke
				(width 0.1524)
				(type default)
			)
			(layer "B.SilkS")
		)
		(fp_line
			(start 0.7874 0.4064)
			(end 0.7874 -0.4064)
			(stroke
				(width 0.1524)
				(type default)
			)
			(layer "B.SilkS")
		)
		(fp_line
			(start -0.67945 -0.3048)
			(end -0.67945 0.3048)
			(stroke
				(width 0.1)
				(type default)
			)
			(layer "B.Fab")
		)
		(fp_line
			(start -0.67945 0.3048)
			(end -0.120396 0.3048)
			(stroke
				(width 0.1)
				(type default)
			)
			(layer "B.Fab")
		)
		(fp_line
			(start -0.12065 -0.3048)
			(end -0.67945 -0.3048)
			(stroke
				(width 0.1)
				(type default)
			)
			(layer "B.Fab")
		)
		(fp_line
			(start -0.12065 -0.2794)
			(end -0.12065 -0.3048)
			(stroke
				(width 0.1)
				(type default)
			)
			(layer "B.Fab")
		)
		(fp_line
			(start -0.120396 0.2794)
			(end 0.12065 0.2794)
			(stroke
				(width 0.1)
				(type default)
			)
			(layer "B.Fab")
		)
		(fp_line
			(start -0.120396 0.3048)
			(end -0.120396 0.2794)
			(stroke
				(width 0.1)
				(type default)
			)
			(layer "B.Fab")
		)
		(fp_line
			(start 0.12065 -0.305054)
			(end 0.12065 -0.2794)
			(stroke
				(width 0.1)
				(type default)
			)
			(layer "B.Fab")
		)
		(fp_line
			(start 0.12065 -0.2794)
			(end -0.12065 -0.2794)
			(stroke
				(width 0.1)
				(type default)
			)
			(layer "B.Fab")
		)
		(fp_line
			(start 0.12065 0.2794)
			(end 0.12065 0.3048)
			(stroke
				(width 0.1)
				(type default)
			)
			(layer "B.Fab")
		)
		(fp_line
			(start 0.12065 0.3048)
			(end 0.67945 0.3048)
			(stroke
				(width 0.1)
				(type default)
			)
			(layer "B.Fab")
		)
		(fp_line
			(start 0.67945 -0.305054)
			(end 0.12065 -0.305054)
			(stroke
				(width 0.1)
				(type default)
			)
			(layer "B.Fab")
		)
		(fp_line
			(start 0.67945 0.3048)
			(end 0.67945 -0.305054)
			(stroke
				(width 0.1)
				(type default)
			)
			(layer "B.Fab")
		)
		(pad "1" smd circle
			(at 0.40005 0 180)
			(size 0 0)
			(layers "B.Cu" "B.Mask" "B.Paste")
			(net "P3V3_AUX")
		)
		(pad "2" smd circle
			(at -0.40005 0 180)
			(size 0 0)
			(layers "B.Cu" "B.Mask" "B.Paste")
			(net "GND")
		)
	)
	(footprint ""
		(layer "B.Cu")
		(at 242.443 -234.061 90)
		(property "Reference" "R1159"
			(at 0 0 90)
			(layer "B.SilkS")
			(hide yes)
			(effects
				(font
					(size 1.27 1.27)
				)
				(justify mirror)
			)
		)
		(property "Value" ""
			(at 0 0 90)
			(layer "B.Fab")
			(effects
				(font
					(size 1.27 1.27)
				)
				(justify mirror)
			)
		)
		(duplicate_pad_numbers_are_jumpers no)
		(fp_line
			(start 0.7874 -0.4064)
			(end -0.7874 -0.4064)
			(stroke
				(width 0.1524)
				(type default)
			)
			(layer "B.SilkS")
		)
		(fp_line
			(start -0.7874 -0.4064)
			(end -0.7874 0.4064)
			(stroke
				(width 0.1524)
				(type default)
			)
			(layer "B.SilkS")
		)
		(fp_line
			(start 0.7874 0.4064)
			(end 0.7874 -0.4064)
			(stroke
				(width 0.1524)
				(type default)
			)
			(layer "B.SilkS")
		)
		(fp_line
			(start -0.7874 0.4064)
			(end 0.7874 0.4064)
			(stroke
				(width 0.1524)
				(type default)
			)
			(layer "B.SilkS")
		)
		(fp_line
			(start 0.67945 -0.305054)
			(end 0.12065 -0.305054)
			(stroke
				(width 0.1)
				(type default)
			)
			(layer "B.Fab")
		)
		(fp_line
			(start 0.12065 -0.305054)
			(end 0.12065 -0.2794)
			(stroke
				(width 0.1)
				(type default)
			)
			(layer "B.Fab")
		)
		(fp_line
			(start -0.12065 -0.3048)
			(end -0.67945 -0.3048)
			(stroke
				(width 0.1)
				(type default)
			)
			(layer "B.Fab")
		)
		(fp_line
			(start -0.67945 -0.3048)
			(end -0.67945 0.3048)
			(stroke
				(width 0.1)
				(type default)
			)
			(layer "B.Fab")
		)
		(fp_line
			(start 0.12065 -0.2794)
			(end -0.12065 -0.2794)
			(stroke
				(width 0.1)
				(type default)
			)
			(layer "B.Fab")
		)
		(fp_line
			(start -0.12065 -0.2794)
			(end -0.12065 -0.3048)
			(stroke
				(width 0.1)
				(type default)
			)
			(layer "B.Fab")
		)
		(fp_line
			(start 0.12065 0.2794)
			(end 0.12065 0.3048)
			(stroke
				(width 0.1)
				(type default)
			)
			(layer "B.Fab")
		)
		(fp_line
			(start -0.120396 0.2794)
			(end 0.12065 0.2794)
			(stroke
				(width 0.1)
				(type default)
			)
			(layer "B.Fab")
		)
		(fp_line
			(start 0.67945 0.3048)
			(end 0.67945 -0.305054)
			(stroke
				(width 0.1)
				(type default)
			)
			(layer "B.Fab")
		)
		(fp_line
			(start 0.12065 0.3048)
			(end 0.67945 0.3048)
			(stroke
				(width 0.1)
				(type default)
			)
			(layer "B.Fab")
		)
		(fp_line
			(start -0.120396 0.3048)
			(end -0.120396 0.2794)
			(stroke
				(width 0.1)
				(type default)
			)
			(layer "B.Fab")
		)
		(fp_line
			(start -0.67945 0.3048)
			(end -0.120396 0.3048)
			(stroke
				(width 0.1)
				(type default)
			)
			(layer "B.Fab")
		)
		(pad "1" smd circle
			(at 0.40005 0 270)
			(size 0 0)
			(layers "B.Cu" "B.Mask" "B.Paste")
			(net "SMB_CPU0_SEC_R_SCL")
		)
		(pad "2" smd circle
			(at -0.40005 0 270)
			(size 0 0)
			(layers "B.Cu" "B.Mask" "B.Paste")
			(net "SMB_CPU0_SEC_SCL")
		)
	)
)
